(kicad_pcb
	(version 20260206)
	(generator "pcbnew")
	(generator_version "10.0")
	(general
		(thickness 1.6)
		(legacy_teardrops no)
	)
	(paper "A4")
	(title_block
		(title "Bryce Canyon_F.DPB_16315-1-OCP.brd")
		(comment 1 "Bryce Canyon / footprints 1410-1416 of 2223")
	)
	(layers
		(0 "F.Cu" signal "TOP")
		(4 "In1.Cu" signal "L2GND")
		(6 "In2.Cu" signal "L3")
		(8 "In3.Cu" signal "L4GND")
		(10 "In4.Cu" signal "L5")
		(12 "In5.Cu" signal "L6VCC")
		(14 "In6.Cu" signal "L7VCC")
		(16 "In7.Cu" signal "L8")
		(18 "In8.Cu" signal "L9GND")
		(20 "In9.Cu" signal "L10")
		(22 "In10.Cu" signal "L11GND")
		(2 "B.Cu" signal "BOTTOM")
		(9 "F.Adhes" user "F.Adhesive")
		(11 "B.Adhes" user "B.Adhesive")
		(13 "F.Paste" user "Package Geometry/Pastemask Top")
		(15 "B.Paste" user "Package Geometry/Pastemask Bottom")
		(5 "F.SilkS" user "Ref Des/Silkscreen Top")
		(7 "B.SilkS" user "Ref Des/Silkscreen Bottom")
		(1 "F.Mask" user "Board Geometry/Soldermask Top")
		(3 "B.Mask" user "Board Geometry/Soldermask Bottom")
		(17 "Dwgs.User" user "User.Drawings")
		(19 "Cmts.User" user "User.Comments")
		(21 "Eco1.User" user "User.Eco1")
		(23 "Eco2.User" user "User.Eco2")
		(25 "Edge.Cuts" user "Board Geometry/Outline")
		(27 "Margin" user)
		(31 "F.CrtYd" user "Package Geometry/Place Bound Top")
		(29 "B.CrtYd" user "Package Geometry/Place Bound Bottom")
		(35 "F.Fab" user "Ref Des/Assembly Top")
		(33 "B.Fab" user "Ref Des/Assembly Bottom")
	)
	(footprint ""
		(layer "F.Cu")
		(at 302.8442 -67.784472 180)
		(property "Reference" "R356"
			(at 0 0 180)
			(layer "F.SilkS")
			(hide yes)
			(effects
				(font
					(size 1.27 1.27)
				)
			)
		)
		(property "Value" "0R2J-2-GP"
			(at 0.064008 -3.993896 180)
			(unlocked yes)
			(layer "F.Fab")
			(hide yes)
			(effects
				(font
					(size 1.016 1.016)
					(thickness 0.1524)
				)
			)
		)
		(property "Device Type" "R402H16"
			(at 0.064008 -5.517896 180)
			(unlocked yes)
			(layer "F.Fab")
			(hide yes)
			(effects
				(font
					(size 1.016 1.016)
					(thickness 0.1524)
				)
			)
		)
		(duplicate_pad_numbers_are_jumpers no)
		(fp_line
			(start 0.508 -0.9398)
			(end -0.508 -0.9398)
			(stroke
				(width 0.1524)
				(type default)
			)
			(layer "F.SilkS")
		)
		(fp_line
			(start -0.508 -0.9398)
			(end -0.508 0.9398)
			(stroke
				(width 0.1524)
				(type default)
			)
			(layer "F.SilkS")
		)
		(fp_rect
			(start -0.508 0.9398)
			(end 0.508 -0.9398)
			(stroke
				(width 0)
				(type default)
			)
			(fill no)
			(layer "F.CrtYd")
		)
		(fp_rect
			(start -0.508 0.9398)
			(end 0.508 -0.9398)
			(stroke
				(width 0)
				(type default)
			)
			(fill no)
			(layer "F.Fab")
		)
		(pad "1" smd custom
			(at 0 -0.4445 180)
			(size 0.1397 0.1397)
			(layers "F.Cu" "F.Mask" "F.Paste")
			(net "I2C_BMC_B_COMP_B_SCL")
			(options
				(clearance outline)
				(anchor circle)
			)
			(primitives
				(gr_poly
					(pts
						(arc
							(start -0.1778 -0.2794)
							(mid -0.249642 -0.249642)
							(end -0.2794 -0.1778)
						)
						(arc
							(start -0.2794 0.1778)
							(mid -0.249642 0.249642)
							(end -0.1778 0.2794)
						)
						(arc
							(start 0.1778 0.2794)
							(mid 0.249642 0.249642)
							(end 0.2794 0.1778)
						)
						(arc
							(start 0.2794 -0.1778)
							(mid 0.249642 -0.249642)
							(end 0.1778 -0.2794)
						)
					)
					(width 0)
					(fill yes)
				)
			)
		)
		(pad "2" smd custom
			(at 0 0.4445 180)
			(size 0.1397 0.1397)
			(layers "F.Cu" "F.Mask" "F.Paste")
			(net "I2C_BMC_B_COMP_B_SCL_R")
			(options
				(clearance outline)
				(anchor circle)
			)
			(primitives
				(gr_poly
					(pts
						(arc
							(start -0.1778 -0.2794)
							(mid -0.249642 -0.249642)
							(end -0.2794 -0.1778)
						)
						(arc
							(start -0.2794 0.1778)
							(mid -0.249642 0.249642)
							(end -0.1778 0.2794)
						)
						(arc
							(start 0.1778 0.2794)
							(mid 0.249642 0.249642)
							(end 0.2794 0.1778)
						)
						(arc
							(start 0.2794 -0.1778)
							(mid 0.249642 -0.249642)
							(end 0.1778 -0.2794)
						)
					)
					(width 0)
					(fill yes)
				)
			)
		)
	)
	(footprint ""
		(layer "F.Cu")
		(at 156.92374 -142.893796 -90)
		(property "Reference" "R1063"
			(at 0 0 270)
			(layer "F.SilkS")
			(hide yes)
			(effects
				(font
					(size 1.27 1.27)
				)
			)
		)
		(property "Value" "49K9R2F-L-GP"
			(at 0.064008 -3.993896 270)
			(unlocked yes)
			(layer "F.Fab")
			(hide yes)
			(effects
				(font
					(size 1.016 1.016)
					(thickness 0.1524)
				)
			)
		)
		(property "Device Type" "R402H16"
			(at 0.064008 -5.517896 270)
			(unlocked yes)
			(layer "F.Fab")
			(hide yes)
			(effects
				(font
					(size 1.016 1.016)
					(thickness 0.1524)
				)
			)
		)
		(duplicate_pad_numbers_are_jumpers no)
		(fp_line
			(start -0.508 -0.9398)
			(end -0.508 0.9398)
			(stroke
				(width 0.1524)
				(type default)
			)
			(layer "F.SilkS")
		)
		(fp_line
			(start 0.508 -0.9398)
			(end -0.508 -0.9398)
			(stroke
				(width 0.1524)
				(type default)
			)
			(layer "F.SilkS")
		)
		(fp_rect
			(start -0.508 0.9398)
			(end 0.508 -0.9398)
			(stroke
				(width 0)
				(type default)
			)
			(fill no)
			(layer "F.CrtYd")
		)
		(fp_rect
			(start -0.508 0.9398)
			(end 0.508 -0.9398)
			(stroke
				(width 0)
				(type default)
			)
			(fill no)
			(layer "F.Fab")
		)
		(pad "1" smd custom
			(at 0 -0.4445 270)
			(size 0.1397 0.1397)
			(layers "F.Cu" "F.Mask" "F.Paste")
			(net "P12V_A")
			(options
				(clearance outline)
				(anchor circle)
			)
			(primitives
				(gr_poly
					(pts
						(arc
							(start -0.1778 -0.2794)
							(mid -0.249642 -0.249642)
							(end -0.2794 -0.1778)
						)
						(arc
							(start -0.2794 0.1778)
							(mid -0.249642 0.249642)
							(end -0.1778 0.2794)
						)
						(arc
							(start 0.1778 0.2794)
							(mid 0.249642 0.249642)
							(end 0.2794 0.1778)
						)
						(arc
							(start 0.2794 -0.1778)
							(mid 0.249642 -0.249642)
							(end 0.1778 -0.2794)
						)
					)
					(width 0)
					(fill yes)
				)
			)
		)
		(pad "2" smd custom
			(at 0 0.4445 270)
			(size 0.1397 0.1397)
			(layers "F.Cu" "F.Mask" "F.Paste")
			(net "MB0_CM_OV_R")
			(options
				(clearance outline)
				(anchor circle)
			)
			(primitives
				(gr_poly
					(pts
						(arc
							(start -0.1778 -0.2794)
							(mid -0.249642 -0.249642)
							(end -0.2794 -0.1778)
						)
						(arc
							(start -0.2794 0.1778)
							(mid -0.249642 0.249642)
							(end -0.1778 0.2794)
						)
						(arc
							(start 0.1778 0.2794)
							(mid 0.249642 0.249642)
							(end 0.2794 0.1778)
						)
						(arc
							(start 0.2794 -0.1778)
							(mid 0.249642 -0.249642)
							(end 0.1778 -0.2794)
						)
					)
					(width 0)
					(fill yes)
				)
			)
		)
	)
	(footprint ""
		(layer "F.Cu")
		(at 361.369102 -189.335918 180)
		(property "Reference" "C294"
			(at 0 0 180)
			(layer "F.SilkS")
			(hide yes)
			(effects
				(font
					(size 1.27 1.27)
				)
			)
		)
		(property "Value" "SC1U25V3KX-GP"
			(at 0 -2.8194 180)
			(unlocked yes)
			(layer "F.Fab")
			(hide yes)
			(effects
				(font
					(size 1.016 1.016)
					(thickness 0.1524)
				)
			)
		)
		(property "Device Type" "C603H36"
			(at 0 -4.3434 180)
			(unlocked yes)
			(layer "F.Fab")
			(hide yes)
			(effects
				(font
					(size 1.016 1.016)
					(thickness 0.1524)
				)
			)
		)
		(duplicate_pad_numbers_are_jumpers no)
		(fp_line
			(start 0.508 0)
			(end -0.508 0)
			(stroke
				(width 0.2032)
				(type default)
			)
			(layer "F.SilkS")
		)
		(fp_rect
			(start -0.5842 1.3335)
			(end 0.5842 -1.3335)
			(stroke
				(width 0)
				(type default)
			)
			(fill no)
			(layer "F.CrtYd")
		)
		(fp_rect
			(start -0.5842 1.3335)
			(end 0.5842 -1.3335)
			(stroke
				(width 0)
				(type default)
			)
			(fill no)
			(layer "F.Fab")
		)
		(pad "1" smd custom
			(at 0 -0.762 180)
			(size 0.2159 0.2159)
			(layers "F.Cu" "F.Mask" "F.Paste")
			(net "P12V_HDD19")
			(options
				(clearance outline)
				(anchor circle)
			)
			(primitives
				(gr_poly
					(pts
						(arc
							(start -0.3302 -0.4318)
							(mid -0.402042 -0.402042)
							(end -0.4318 -0.3302)
						)
						(arc
							(start -0.4318 0.3302)
							(mid -0.402042 0.402042)
							(end -0.3302 0.4318)
						)
						(arc
							(start 0.3302 0.4318)
							(mid 0.402042 0.402042)
							(end 0.4318 0.3302)
						)
						(arc
							(start 0.4318 -0.3302)
							(mid 0.402042 -0.402042)
							(end 0.3302 -0.4318)
						)
					)
					(width 0)
					(fill yes)
				)
			)
		)
		(pad "2" smd custom
			(at 0 0.762 180)
			(size 0.2159 0.2159)
			(layers "F.Cu" "F.Mask" "F.Paste")
			(net "GND")
			(options
				(clearance outline)
				(anchor circle)
			)
			(primitives
				(gr_poly
					(pts
						(arc
							(start -0.3302 -0.4318)
							(mid -0.402042 -0.402042)
							(end -0.4318 -0.3302)
						)
						(arc
							(start -0.4318 0.3302)
							(mid -0.402042 0.402042)
							(end -0.3302 0.4318)
						)
						(arc
							(start 0.3302 0.4318)
							(mid 0.402042 0.402042)
							(end 0.4318 0.3302)
						)
						(arc
							(start 0.4318 -0.3302)
							(mid 0.402042 -0.402042)
							(end 0.3302 -0.4318)
						)
					)
					(width 0)
					(fill yes)
				)
			)
		)
	)
	(footprint ""
		(layer "F.Cu")
		(at 317.881 -180.064918 -90)
		(property "Reference" "R548"
			(at 0 0 270)
			(layer "F.SilkS")
			(hide yes)
			(effects
				(font
					(size 1.27 1.27)
				)
			)
		)
		(property "Value" "220R3F-1-GP"
			(at -0.0254 -2.5146 270)
			(unlocked yes)
			(layer "F.Fab")
			(hide yes)
			(effects
				(font
					(size 1.016 1.016)
					(thickness 0.1524)
				)
			)
		)
		(property "Device Type" "R603H22"
			(at -0.0254 -4.0386 270)
			(unlocked yes)
			(layer "F.Fab")
			(hide yes)
			(effects
				(font
					(size 1.016 1.016)
					(thickness 0.1524)
				)
			)
		)
		(duplicate_pad_numbers_are_jumpers no)
		(fp_line
			(start -0.4826 0)
			(end -0.2032 0)
			(stroke
				(width 0.2032)
				(type default)
			)
			(layer "F.SilkS")
		)
		(fp_line
			(start 0.2032 0)
			(end 0.4826 0)
			(stroke
				(width 0.2032)
				(type default)
			)
			(layer "F.SilkS")
		)
		(fp_rect
			(start -0.5842 1.3335)
			(end 0.5842 -1.3335)
			(stroke
				(width 0)
				(type default)
			)
			(fill no)
			(layer "F.CrtYd")
		)
		(fp_rect
			(start -0.5842 1.3335)
			(end 0.5842 -1.3335)
			(stroke
				(width 0)
				(type default)
			)
			(fill no)
			(layer "F.Fab")
		)
		(pad "1" smd custom
			(at 0 -0.762 270)
			(size 0.2159 0.2159)
			(layers "F.Cu" "F.Mask" "F.Paste")
			(net "HDD_PRSNT_18")
			(options
				(clearance outline)
				(anchor circle)
			)
			(primitives
				(gr_poly
					(pts
						(arc
							(start -0.3302 -0.4318)
							(mid -0.402042 -0.402042)
							(end -0.4318 -0.3302)
						)
						(arc
							(start -0.4318 0.3302)
							(mid -0.402042 0.402042)
							(end -0.3302 0.4318)
						)
						(arc
							(start 0.3302 0.4318)
							(mid 0.402042 0.402042)
							(end 0.4318 0.3302)
						)
						(arc
							(start 0.4318 -0.3302)
							(mid 0.402042 -0.402042)
							(end 0.3302 -0.4318)
						)
					)
					(width 0)
					(fill yes)
				)
			)
		)
		(pad "2" smd custom
			(at 0 0.762 270)
			(size 0.2159 0.2159)
			(layers "F.Cu" "F.Mask" "F.Paste")
			(net "DRIVE_A_18_INS")
			(options
				(clearance outline)
				(anchor circle)
			)
			(primitives
				(gr_poly
					(pts
						(arc
							(start -0.3302 -0.4318)
							(mid -0.402042 -0.402042)
							(end -0.4318 -0.3302)
						)
						(arc
							(start -0.4318 0.3302)
							(mid -0.402042 0.402042)
							(end -0.3302 0.4318)
						)
						(arc
							(start 0.3302 0.4318)
							(mid 0.402042 0.402042)
							(end 0.4318 0.3302)
						)
						(arc
							(start 0.4318 -0.3302)
							(mid 0.402042 -0.402042)
							(end 0.3302 -0.4318)
						)
					)
					(width 0)
					(fill yes)
				)
			)
		)
	)
	(footprint ""
		(layer "F.Cu")
		(at 467.618318 -41.52265 180)
		(property "Reference" "R945"
			(at 0 0 180)
			(layer "F.SilkS")
			(hide yes)
			(effects
				(font
					(size 1.27 1.27)
				)
			)
		)
		(property "Value" "0R2J-2-GP"
			(at 0.064008 -3.993896 180)
			(unlocked yes)
			(layer "F.Fab")
			(hide yes)
			(effects
				(font
					(size 1.016 1.016)
					(thickness 0.1524)
				)
			)
		)
		(property "Device Type" "R402H16"
			(at 0.064008 -5.517896 180)
			(unlocked yes)
			(layer "F.Fab")
			(hide yes)
			(effects
				(font
					(size 1.016 1.016)
					(thickness 0.1524)
				)
			)
		)
		(duplicate_pad_numbers_are_jumpers no)
		(fp_line
			(start 0.508 -0.9398)
			(end -0.508 -0.9398)
			(stroke
				(width 0.1524)
				(type default)
			)
			(layer "F.SilkS")
		)
		(fp_line
			(start -0.508 -0.9398)
			(end -0.508 0.9398)
			(stroke
				(width 0.1524)
				(type default)
			)
			(layer "F.SilkS")
		)
		(fp_rect
			(start -0.508 0.9398)
			(end 0.508 -0.9398)
			(stroke
				(width 0)
				(type default)
			)
			(fill no)
			(layer "F.CrtYd")
		)
		(fp_rect
			(start -0.508 0.9398)
			(end 0.508 -0.9398)
			(stroke
				(width 0)
				(type default)
			)
			(fill no)
			(layer "F.Fab")
		)
		(pad "1" smd custom
			(at 0 -0.4445 180)
			(size 0.1397 0.1397)
			(layers "F.Cu" "F.Mask" "F.Paste")
			(net "DRIVE_A_35_PWR")
			(options
				(clearance outline)
				(anchor circle)
			)
			(primitives
				(gr_poly
					(pts
						(arc
							(start -0.1778 -0.2794)
							(mid -0.249642 -0.249642)
							(end -0.2794 -0.1778)
						)
						(arc
							(start -0.2794 0.1778)
							(mid -0.249642 0.249642)
							(end -0.1778 0.2794)
						)
						(arc
							(start 0.1778 0.2794)
							(mid 0.249642 0.249642)
							(end 0.2794 0.1778)
						)
						(arc
							(start 0.2794 -0.1778)
							(mid 0.249642 -0.249642)
							(end 0.1778 -0.2794)
						)
					)
					(width 0)
					(fill yes)
				)
			)
		)
		(pad "2" smd custom
			(at 0 0.4445 180)
			(size 0.1397 0.1397)
			(layers "F.Cu" "F.Mask" "F.Paste")
			(net "SW_PWR_R_HDD35")
			(options
				(clearance outline)
				(anchor circle)
			)
			(primitives
				(gr_poly
					(pts
						(arc
							(start -0.1778 -0.2794)
							(mid -0.249642 -0.249642)
							(end -0.2794 -0.1778)
						)
						(arc
							(start -0.2794 0.1778)
							(mid -0.249642 0.249642)
							(end -0.1778 0.2794)
						)
						(arc
							(start 0.1778 0.2794)
							(mid 0.249642 0.249642)
							(end 0.2794 0.1778)
						)
						(arc
							(start 0.2794 -0.1778)
							(mid 0.249642 -0.249642)
							(end 0.1778 -0.2794)
						)
					)
					(width 0)
					(fill yes)
				)
			)
		)
	)
	(footprint ""
		(layer "F.Cu")
		(at 244.8306 -242.6716)
		(property "Reference" "R77"
			(at 0 0 0)
			(layer "F.SilkS")
			(hide yes)
			(effects
				(font
					(size 1.27 1.27)
				)
			)
		)
		(property "Value" "4K7R2F-GP"
			(at 0.064008 -3.993896 0)
			(unlocked yes)
			(layer "F.Fab")
			(hide yes)
			(effects
				(font
					(size 1.016 1.016)
					(thickness 0.1524)
				)
			)
		)
		(property "Device Type" "R402H16"
			(at 0.064008 -5.517896 0)
			(unlocked yes)
			(layer "F.Fab")
			(hide yes)
			(effects
				(font
					(size 1.016 1.016)
					(thickness 0.1524)
				)
			)
		)
		(duplicate_pad_numbers_are_jumpers no)
		(fp_line
			(start -0.508 -0.9398)
			(end -0.508 0.9398)
			(stroke
				(width 0.1524)
				(type default)
			)
			(layer "F.SilkS")
		)
		(fp_line
			(start 0.508 -0.9398)
			(end -0.508 -0.9398)
			(stroke
				(width 0.1524)
				(type default)
			)
			(layer "F.SilkS")
		)
		(fp_rect
			(start -0.508 0.9398)
			(end 0.508 -0.9398)
			(stroke
				(width 0)
				(type default)
			)
			(fill no)
			(layer "F.CrtYd")
		)
		(fp_rect
			(start -0.508 0.9398)
			(end 0.508 -0.9398)
			(stroke
				(width 0)
				(type default)
			)
			(fill no)
			(layer "F.Fab")
		)
		(pad "1" smd custom
			(at 0 -0.4445)
			(size 0.1397 0.1397)
			(layers "F.Cu" "F.Mask" "F.Paste")
			(net "P3V3_STBY_A")
			(options
				(clearance outline)
				(anchor circle)
			)
			(primitives
				(gr_poly
					(pts
						(arc
							(start -0.1778 -0.2794)
							(mid -0.249642 -0.249642)
							(end -0.2794 -0.1778)
						)
						(arc
							(start -0.2794 0.1778)
							(mid -0.249642 0.249642)
							(end -0.1778 0.2794)
						)
						(arc
							(start 0.1778 0.2794)
							(mid 0.249642 0.249642)
							(end 0.2794 0.1778)
						)
						(arc
							(start 0.2794 -0.1778)
							(mid 0.249642 -0.249642)
							(end 0.1778 -0.2794)
						)
					)
					(width 0)
					(fill yes)
				)
			)
		)
		(pad "2" smd custom
			(at 0 0.4445)
			(size 0.1397 0.1397)
			(layers "F.Cu" "F.Mask" "F.Paste")
			(net "IO_EXP2_A0")
			(options
				(clearance outline)
				(anchor circle)
			)
			(primitives
				(gr_poly
					(pts
						(arc
							(start -0.1778 -0.2794)
							(mid -0.249642 -0.249642)
							(end -0.2794 -0.1778)
						)
						(arc
							(start -0.2794 0.1778)
							(mid -0.249642 0.249642)
							(end -0.1778 0.2794)
						)
						(arc
							(start 0.1778 0.2794)
							(mid 0.249642 0.249642)
							(end 0.2794 0.1778)
						)
						(arc
							(start 0.2794 -0.1778)
							(mid 0.249642 -0.249642)
							(end 0.1778 -0.2794)
						)
					)
					(width 0)
					(fill yes)
				)
			)
		)
	)
	(footprint ""
		(layer "F.Cu")
		(at 444.4619 -292.169342 90)
		(property "Reference" "R360"
			(at 0 0 90)
			(layer "F.SilkS")
			(hide yes)
			(effects
				(font
					(size 1.27 1.27)
				)
			)
		)
		(property "Value" "10KR2F-2-GP"
			(at 0.064008 -3.993896 90)
			(unlocked yes)
			(layer "F.Fab")
			(hide yes)
			(effects
				(font
					(size 1.016 1.016)
					(thickness 0.1524)
				)
			)
		)
		(property "Device Type" "R402H16"
			(at 0.064008 -5.517896 90)
			(unlocked yes)
			(layer "F.Fab")
			(hide yes)
			(effects
				(font
					(size 1.016 1.016)
					(thickness 0.1524)
				)
			)
		)
		(duplicate_pad_numbers_are_jumpers no)
		(fp_line
			(start 0.508 -0.9398)
			(end -0.508 -0.9398)
			(stroke
				(width 0.1524)
				(type default)
			)
			(layer "F.SilkS")
		)
		(fp_line
			(start -0.508 -0.9398)
			(end -0.508 0.9398)
			(stroke
				(width 0.1524)
				(type default)
			)
			(layer "F.SilkS")
		)
		(fp_rect
			(start -0.508 0.9398)
			(end 0.508 -0.9398)
			(stroke
				(width 0)
				(type default)
			)
			(fill no)
			(layer "F.CrtYd")
		)
		(fp_rect
			(start -0.508 0.9398)
			(end 0.508 -0.9398)
			(stroke
				(width 0)
				(type default)
			)
			(fill no)
			(layer "F.Fab")
		)
		(pad "1" smd custom
			(at 0 -0.4445 90)
			(size 0.1397 0.1397)
			(layers "F.Cu" "F.Mask" "F.Paste")
			(net "P3V3_STBY_A")
			(options
				(clearance outline)
				(anchor circle)
			)
			(primitives
				(gr_poly
					(pts
						(arc
							(start -0.1778 -0.2794)
							(mid -0.249642 -0.249642)
							(end -0.2794 -0.1778)
						)
						(arc
							(start -0.2794 0.1778)
							(mid -0.249642 0.249642)
							(end -0.1778 0.2794)
						)
						(arc
							(start 0.1778 0.2794)
							(mid 0.249642 0.249642)
							(end 0.2794 0.1778)
						)
						(arc
							(start 0.2794 -0.1778)
							(mid 0.249642 -0.249642)
							(end 0.1778 -0.2794)
						)
					)
					(width 0)
					(fill yes)
				)
			)
		)
		(pad "2" smd custom
			(at 0 0.4445 90)
			(size 0.1397 0.1397)
			(layers "F.Cu" "F.Mask" "F.Paste")
			(net "HDD_PRSNT_10")
			(options
				(clearance outline)
				(anchor circle)
			)
			(primitives
				(gr_poly
					(pts
						(arc
							(start -0.1778 -0.2794)
							(mid -0.249642 -0.249642)
							(end -0.2794 -0.1778)
						)
						(arc
							(start -0.2794 0.1778)
							(mid -0.249642 0.249642)
							(end -0.1778 0.2794)
						)
						(arc
							(start 0.1778 0.2794)
							(mid 0.249642 0.249642)
							(end 0.2794 0.1778)
						)
						(arc
							(start 0.2794 -0.1778)
							(mid 0.249642 -0.249642)
							(end 0.1778 -0.2794)
						)
					)
					(width 0)
					(fill yes)
				)
			)
		)
	)
)
